# SCM (Grand Teton) — schematic netlist excerpt (pin names and nets, part order shuffled) for the footprints in the layout excerpt that follows; sources: Cadence DE-HDL packaged netlist, KiCad conversion of 12092022_DA0F0TMDCD0_F0T_Management_Board_D_brd_V3_OCP.brd

R821  Q_RES  4.7K 1% EMPTY  pkg 0402LF  page 13 : A = P3V3_AUX ; B = FM_BMC_ONCTL_R_N
C118  Q_CAP  22UF 6.3V 20% X6S  pkg C0603  page 16 : A = P1V0_AUX ; B = GND

(kicad_pcb
	(version 20260206)
	(generator "pcbnew")
	(generator_version "10.0")
	(general
		(thickness 1.6)
		(legacy_teardrops no)
	)
	(paper "A4")
	(title_block
		(title "12092022_DA0F0TMDCD0_F0T_Management_Board_D_brd_V3_OCP.brd")
		(comment 1 "Grand Teton / footprints 936-937 of 1440")
	)
	(layers
		(0 "F.Cu" signal "TOP")
		(4 "In1.Cu" signal "GND")
		(6 "In2.Cu" signal "IN1")
		(8 "In3.Cu" signal "GND1")
		(10 "In4.Cu" signal "IN2")
		(12 "In5.Cu" signal "VCC")
		(14 "In6.Cu" signal "VCC1")
		(16 "In7.Cu" signal "IN3")
		(18 "In8.Cu" signal "GND2")
		(20 "In9.Cu" signal "IN4")
		(22 "In10.Cu" signal "GND3")
		(2 "B.Cu" signal "BOTTOM")
		(9 "F.Adhes" user "F.Adhesive")
		(11 "B.Adhes" user "B.Adhesive")
		(13 "F.Paste" user "Package Geometry/Pastemask Top")
		(15 "B.Paste" user "Package Geometry/Pastemask Bottom")
		(5 "F.SilkS" user "Ref Des/Silkscreen Top")
		(7 "B.SilkS" user "Ref Des/Silkscreen Bottom")
		(1 "F.Mask" user "Board Geometry/Soldermask Top")
		(3 "B.Mask" user "Board Geometry/Soldermask Bottom")
		(17 "Dwgs.User" user "User.Drawings")
		(19 "Cmts.User" user "User.Comments")
		(21 "Eco1.User" user "User.Eco1")
		(23 "Eco2.User" user "User.Eco2")
		(25 "Edge.Cuts" user "Board Geometry/Outline")
		(27 "Margin" user)
		(31 "F.CrtYd" user "Package Geometry/Place Bound Top")
		(29 "B.CrtYd" user "Package Geometry/Place Bound Bottom")
		(35 "F.Fab" user "Ref Des/Assembly Top")
		(33 "B.Fab" user "Ref Des/Assembly Bottom")
	)
	(footprint ""
		(layer "B.Cu")
		(at 74.810112 -56.937656 -90)
		(property "Reference" "C118"
			(at 0 0 90)
			(layer "B.SilkS")
			(hide yes)
			(effects
				(font
					(size 1.27 1.27)
				)
				(justify mirror)
			)
		)
		(property "Value" ""
			(at 0 0 90)
			(layer "B.Fab")
			(effects
				(font
					(size 1.27 1.27)
				)
				(justify mirror)
			)
		)
		(duplicate_pad_numbers_are_jumpers no)
		(fp_line
			(start -1.2954 0.5842)
			(end 1.2954 0.5842)
			(stroke
				(width 0.1524)
				(type default)
			)
			(layer "B.SilkS")
		)
		(fp_line
			(start 1.2954 0.5842)
			(end 1.2954 -0.5842)
			(stroke
				(width 0.1524)
				(type default)
			)
			(layer "B.SilkS")
		)
		(fp_line
			(start -1.2954 -0.5842)
			(end -1.2954 0.5842)
			(stroke
				(width 0.1524)
				(type default)
			)
			(layer "B.SilkS")
		)
		(fp_line
			(start 0 -0.5842)
			(end 0 0.5842)
			(stroke
				(width 0.1524)
				(type default)
			)
			(layer "B.SilkS")
		)
		(fp_line
			(start 1.2954 -0.5842)
			(end -1.2954 -0.5842)
			(stroke
				(width 0.1524)
				(type default)
			)
			(layer "B.SilkS")
		)
		(fp_line
			(start -0.8636 0.4572)
			(end 0.8636 0.4572)
			(stroke
				(width 0.1)
				(type default)
			)
			(layer "B.Fab")
		)
		(fp_line
			(start 0.8636 0.4572)
			(end 0.8636 0.4064)
			(stroke
				(width 0.1)
				(type default)
			)
			(layer "B.Fab")
		)
		(fp_line
			(start -1.1938 0.4064)
			(end -0.8636 0.4064)
			(stroke
				(width 0.1)
				(type default)
			)
			(layer "B.Fab")
		)
		(fp_line
			(start -0.8636 0.4064)
			(end -0.8636 0.4572)
			(stroke
				(width 0.1)
				(type default)
			)
			(layer "B.Fab")
		)
		(fp_line
			(start 0.8636 0.4064)
			(end 1.1938 0.4064)
			(stroke
				(width 0.1)
				(type default)
			)
			(layer "B.Fab")
		)
		(fp_line
			(start 1.1938 0.4064)
			(end 1.1938 -0.4064)
			(stroke
				(width 0.1)
				(type default)
			)
			(layer "B.Fab")
		)
		(fp_line
			(start -1.1938 -0.4064)
			(end -1.1938 0.4064)
			(stroke
				(width 0.1)
				(type default)
			)
			(layer "B.Fab")
		)
		(fp_line
			(start -0.8636 -0.4064)
			(end -1.1938 -0.4064)
			(stroke
				(width 0.1)
				(type default)
			)
			(layer "B.Fab")
		)
		(fp_line
			(start 0.8636 -0.4064)
			(end 0.8636 -0.4572)
			(stroke
				(width 0.1)
				(type default)
			)
			(layer "B.Fab")
		)
		(fp_line
			(start 1.1938 -0.4064)
			(end 0.8636 -0.4064)
			(stroke
				(width 0.1)
				(type default)
			)
			(layer "B.Fab")
		)
		(fp_line
			(start -0.8636 -0.4572)
			(end -0.8636 -0.4064)
			(stroke
				(width 0.1)
				(type default)
			)
			(layer "B.Fab")
		)
		(fp_line
			(start 0.8636 -0.4572)
			(end -0.8636 -0.4572)
			(stroke
				(width 0.1)
				(type default)
			)
			(layer "B.Fab")
		)
		(pad "1" smd rect
			(at 0.7366 0 180)
			(size 0.7112 0.8128)
			(layers "B.Cu" "B.Mask" "B.Paste")
			(net "P1V0_AUX")
		)
		(pad "2" smd rect
			(at -0.7366 0 180)
			(size 0.7112 0.8128)
			(layers "B.Cu" "B.Mask" "B.Paste")
			(net "GND")
		)
	)
	(footprint ""
		(layer "B.Cu")
		(at 39.414958 -83.861656 180)
		(property "Reference" "R821"
			(at 0 0 0)
			(layer "B.SilkS")
			(hide yes)
			(effects
				(font
					(size 1.27 1.27)
				)
				(justify mirror)
			)
		)
		(property "Value" ""
			(at 0 0 0)
			(layer "B.Fab")
			(effects
				(font
					(size 1.27 1.27)
				)
				(justify mirror)
			)
		)
		(duplicate_pad_numbers_are_jumpers no)
		(fp_line
			(start 0.7874 0.4064)
			(end 0.7874 -0.4064)
			(stroke
				(width 0.1524)
				(type default)
			)
			(layer "B.SilkS")
		)
		(fp_line
			(start 0.7874 -0.4064)
			(end -0.7874 -0.4064)
			(stroke
				(width 0.1524)
				(type default)
			)
			(layer "B.SilkS")
		)
		(fp_line
			(start -0.7874 0.4064)
			(end 0.7874 0.4064)
			(stroke
				(width 0.1524)
				(type default)
			)
			(layer "B.SilkS")
		)
		(fp_line
			(start -0.7874 -0.4064)
			(end -0.7874 0.4064)
			(stroke
				(width 0.1524)
				(type default)
			)
			(layer "B.SilkS")
		)
		(fp_line
			(start 0.67945 0.3048)
			(end 0.67945 -0.305054)
			(stroke
				(width 0.1)
				(type default)
			)
			(layer "B.Fab")
		)
		(fp_line
			(start 0.67945 -0.305054)
			(end 0.12065 -0.305054)
			(stroke
				(width 0.1)
				(type default)
			)
			(layer "B.Fab")
		)
		(fp_line
			(start 0.12065 0.3048)
			(end 0.67945 0.3048)
			(stroke
				(width 0.1)
				(type default)
			)
			(layer "B.Fab")
		)
		(fp_line
			(start 0.12065 0.2794)
			(end 0.12065 0.3048)
			(stroke
				(width 0.1)
				(type default)
			)
			(layer "B.Fab")
		)
		(fp_line
			(start 0.12065 -0.2794)
			(end -0.12065 -0.2794)
			(stroke
				(width 0.1)
				(type default)
			)
			(layer "B.Fab")
		)
		(fp_line
			(start 0.12065 -0.305054)
			(end 0.12065 -0.2794)
			(stroke
				(width 0.1)
				(type default)
			)
			(layer "B.Fab")
		)
		(fp_line
			(start -0.120396 0.3048)
			(end -0.120396 0.2794)
			(stroke
				(width 0.1)
				(type default)
			)
			(layer "B.Fab")
		)
		(fp_line
			(start -0.120396 0.2794)
			(end 0.12065 0.2794)
			(stroke
				(width 0.1)
				(type default)
			)
			(layer "B.Fab")
		)
		(fp_line
			(start -0.12065 -0.2794)
			(end -0.12065 -0.3048)
			(stroke
				(width 0.1)
				(type default)
			)
			(layer "B.Fab")
		)
		(fp_line
			(start -0.12065 -0.3048)
			(end -0.67945 -0.3048)
			(stroke
				(width 0.1)
				(type default)
			)
			(layer "B.Fab")
		)
		(fp_line
			(start -0.67945 0.3048)
			(end -0.120396 0.3048)
			(stroke
				(width 0.1)
				(type default)
			)
			(layer "B.Fab")
		)
		(fp_line
			(start -0.67945 -0.3048)
			(end -0.67945 0.3048)
			(stroke
				(width 0.1)
				(type default)
			)
			(layer "B.Fab")
		)
		(pad "1" smd circle
			(at 0.40005 0)
			(size 0 0)
			(layers "B.Cu" "B.Mask" "B.Paste")
			(net "P3V3_AUX")
		)
		(pad "2" smd circle
			(at -0.40005 0)
			(size 0 0)
			(layers "B.Cu" "B.Mask" "B.Paste")
			(net "FM_BMC_ONCTL_R_N")
		)
	)
)
